(kicad_pcb
	(version 20260206)
	(generator "pcbnew")
	(generator_version "10.0")
	(general
		(thickness 1.6)
		(legacy_teardrops no)
	)
	(paper "A4")
	(title_block
		(title "12092022_DA0F0TMDCD0_F0T_Management_Board_D_brd_V3_OCP.brd")
		(comment 1 "Grand Teton / footprints 751-756 of 1440")
	)
	(layers
		(0 "F.Cu" signal "TOP")
		(4 "In1.Cu" signal "GND")
		(6 "In2.Cu" signal "IN1")
		(8 "In3.Cu" signal "GND1")
		(10 "In4.Cu" signal "IN2")
		(12 "In5.Cu" signal "VCC")
		(14 "In6.Cu" signal "VCC1")
		(16 "In7.Cu" signal "IN3")
		(18 "In8.Cu" signal "GND2")
		(20 "In9.Cu" signal "IN4")
		(22 "In10.Cu" signal "GND3")
		(2 "B.Cu" signal "BOTTOM")
		(9 "F.Adhes" user "F.Adhesive")
		(11 "B.Adhes" user "B.Adhesive")
		(13 "F.Paste" user "Package Geometry/Pastemask Top")
		(15 "B.Paste" user "Package Geometry/Pastemask Bottom")
		(5 "F.SilkS" user "Ref Des/Silkscreen Top")
		(7 "B.SilkS" user "Ref Des/Silkscreen Bottom")
		(1 "F.Mask" user "Board Geometry/Soldermask Top")
		(3 "B.Mask" user "Board Geometry/Soldermask Bottom")
		(17 "Dwgs.User" user "User.Drawings")
		(19 "Cmts.User" user "User.Comments")
		(21 "Eco1.User" user "User.Eco1")
		(23 "Eco2.User" user "User.Eco2")
		(25 "Edge.Cuts" user "Board Geometry/Outline")
		(27 "Margin" user)
		(31 "F.CrtYd" user "Package Geometry/Place Bound Top")
		(29 "B.CrtYd" user "Package Geometry/Place Bound Bottom")
		(35 "F.Fab" user "Ref Des/Assembly Top")
		(33 "B.Fab" user "Ref Des/Assembly Bottom")
	)
	(footprint ""
		(layer "B.Cu")
		(at 20.282408 -92.8116 -90)
		(property "Reference" "C176"
			(at 0 0 90)
			(layer "B.SilkS")
			(hide yes)
			(effects
				(font
					(size 1.27 1.27)
				)
				(justify mirror)
			)
		)
		(property "Value" ""
			(at 0 0 90)
			(layer "B.Fab")
			(effects
				(font
					(size 1.27 1.27)
				)
				(justify mirror)
			)
		)
		(duplicate_pad_numbers_are_jumpers no)
		(fp_line
			(start -0.69215 0.2921)
			(end 0.69215 0.2921)
			(stroke
				(width 0.1524)
				(type default)
			)
			(layer "B.SilkS")
		)
		(fp_line
			(start 0.69215 0.2921)
			(end 0.69215 -0.2921)
			(stroke
				(width 0.1524)
				(type default)
			)
			(layer "B.SilkS")
		)
		(fp_line
			(start -0.69215 -0.2921)
			(end -0.69215 0.2921)
			(stroke
				(width 0.1524)
				(type default)
			)
			(layer "B.SilkS")
		)
		(fp_line
			(start 0.69215 -0.2921)
			(end -0.69215 -0.2921)
			(stroke
				(width 0.1524)
				(type default)
			)
			(layer "B.SilkS")
		)
		(fp_line
			(start -0.51435 0.2794)
			(end 0.51435 0.2794)
			(stroke
				(width 0.1)
				(type default)
			)
			(layer "B.Fab")
		)
		(fp_line
			(start 0.51435 0.2794)
			(end 0.51435 -0.2794)
			(stroke
				(width 0.1)
				(type default)
			)
			(layer "B.Fab")
		)
		(fp_line
			(start -0.51435 -0.2794)
			(end -0.51435 0.2794)
			(stroke
				(width 0.1)
				(type default)
			)
			(layer "B.Fab")
		)
		(fp_line
			(start 0.51435 -0.2794)
			(end -0.51435 -0.2794)
			(stroke
				(width 0.1)
				(type default)
			)
			(layer "B.Fab")
		)
		(pad "1" smd circle
			(at 0.40005 0 90)
			(size 0 0)
			(layers "B.Cu" "B.Mask" "B.Paste")
			(net "PVCCA_AUX_PLD")
		)
		(pad "2" smd circle
			(at -0.40005 0 90)
			(size 0 0)
			(layers "B.Cu" "B.Mask" "B.Paste")
			(net "GND")
		)
		(zone
			(layer "B.Cu")
			(hatch none 0.5)
			(connect_pads
				(clearance 0)
			)
			(min_thickness 0.25)
			(keepout
				(tracks not_allowed)
				(vias allowed)
				(pads allowed)
				(copperpour not_allowed)
				(footprints allowed)
			)
			(placement
				(enabled no)
				(sheetname "")
			)
			(fill
				(thermal_gap 0.5)
				(thermal_bridge_width 0.5)
				(island_removal_mode 0)
			)
			(polygon
				(pts
					(xy 20.194778 -92.6211) (xy 20.136612 -92.71254) (xy 20.136612 -92.91193) (xy 20.194778 -93.0021)
					(xy 20.370038 -93.0021) (xy 20.428458 -92.91193) (xy 20.428458 -92.71254) (xy 20.370292 -92.6211)
				)
			)
		)
	)
	(footprint ""
		(layer "B.Cu")
		(at 31.623 -41.4147 -90)
		(property "Reference" "C203"
			(at 0 0 90)
			(layer "B.SilkS")
			(hide yes)
			(effects
				(font
					(size 1.27 1.27)
				)
				(justify mirror)
			)
		)
		(property "Value" ""
			(at 0 0 90)
			(layer "B.Fab")
			(effects
				(font
					(size 1.27 1.27)
				)
				(justify mirror)
			)
		)
		(duplicate_pad_numbers_are_jumpers no)
		(fp_line
			(start -0.7874 0.4064)
			(end 0.7874 0.4064)
			(stroke
				(width 0.1524)
				(type default)
			)
			(layer "B.SilkS")
		)
		(fp_line
			(start 0.7874 0.4064)
			(end 0.7874 -0.4064)
			(stroke
				(width 0.1524)
				(type default)
			)
			(layer "B.SilkS")
		)
		(fp_line
			(start -0.7874 -0.4064)
			(end -0.7874 0.4064)
			(stroke
				(width 0.1524)
				(type default)
			)
			(layer "B.SilkS")
		)
		(fp_line
			(start 0.7874 -0.4064)
			(end -0.7874 -0.4064)
			(stroke
				(width 0.1524)
				(type default)
			)
			(layer "B.SilkS")
		)
		(fp_line
			(start -0.67945 0.3048)
			(end -0.120396 0.3048)
			(stroke
				(width 0.1)
				(type default)
			)
			(layer "B.Fab")
		)
		(fp_line
			(start -0.120396 0.3048)
			(end -0.120396 0.2794)
			(stroke
				(width 0.1)
				(type default)
			)
			(layer "B.Fab")
		)
		(fp_line
			(start 0.12065 0.3048)
			(end 0.67945 0.3048)
			(stroke
				(width 0.1)
				(type default)
			)
			(layer "B.Fab")
		)
		(fp_line
			(start 0.67945 0.3048)
			(end 0.67945 -0.305054)
			(stroke
				(width 0.1)
				(type default)
			)
			(layer "B.Fab")
		)
		(fp_line
			(start -0.120396 0.2794)
			(end 0.12065 0.2794)
			(stroke
				(width 0.1)
				(type default)
			)
			(layer "B.Fab")
		)
		(fp_line
			(start 0.12065 0.2794)
			(end 0.12065 0.3048)
			(stroke
				(width 0.1)
				(type default)
			)
			(layer "B.Fab")
		)
		(fp_line
			(start -0.12065 -0.2794)
			(end -0.12065 -0.3048)
			(stroke
				(width 0.1)
				(type default)
			)
			(layer "B.Fab")
		)
		(fp_line
			(start 0.12065 -0.2794)
			(end -0.12065 -0.2794)
			(stroke
				(width 0.1)
				(type default)
			)
			(layer "B.Fab")
		)
		(fp_line
			(start -0.67945 -0.3048)
			(end -0.67945 0.3048)
			(stroke
				(width 0.1)
				(type default)
			)
			(layer "B.Fab")
		)
		(fp_line
			(start -0.12065 -0.3048)
			(end -0.67945 -0.3048)
			(stroke
				(width 0.1)
				(type default)
			)
			(layer "B.Fab")
		)
		(fp_line
			(start 0.12065 -0.305054)
			(end 0.12065 -0.2794)
			(stroke
				(width 0.1)
				(type default)
			)
			(layer "B.Fab")
		)
		(fp_line
			(start 0.67945 -0.305054)
			(end 0.12065 -0.305054)
			(stroke
				(width 0.1)
				(type default)
			)
			(layer "B.Fab")
		)
		(pad "1" smd circle
			(at 0.40005 0 90)
			(size 0 0)
			(layers "B.Cu" "B.Mask" "B.Paste")
			(net "P5V_AUX")
		)
		(pad "2" smd circle
			(at -0.40005 0 90)
			(size 0 0)
			(layers "B.Cu" "B.Mask" "B.Paste")
			(net "GND")
		)
	)
	(footprint ""
		(layer "B.Cu")
		(at 77.2795 -100.935028)
		(property "Reference" "C273"
			(at 0 0 0)
			(layer "B.SilkS")
			(hide yes)
			(effects
				(font
					(size 1.27 1.27)
				)
				(justify mirror)
			)
		)
		(property "Value" ""
			(at 0 0 0)
			(layer "B.Fab")
			(effects
				(font
					(size 1.27 1.27)
				)
				(justify mirror)
			)
		)
		(duplicate_pad_numbers_are_jumpers no)
		(fp_line
			(start -0.7874 -0.4064)
			(end -0.7874 0.4064)
			(stroke
				(width 0.1524)
				(type default)
			)
			(layer "B.SilkS")
		)
		(fp_line
			(start -0.7874 0.4064)
			(end 0.7874 0.4064)
			(stroke
				(width 0.1524)
				(type default)
			)
			(layer "B.SilkS")
		)
		(fp_line
			(start 0.7874 -0.4064)
			(end -0.7874 -0.4064)
			(stroke
				(width 0.1524)
				(type default)
			)
			(layer "B.SilkS")
		)
		(fp_line
			(start 0.7874 0.4064)
			(end 0.7874 -0.4064)
			(stroke
				(width 0.1524)
				(type default)
			)
			(layer "B.SilkS")
		)
		(fp_line
			(start -0.67945 -0.3048)
			(end -0.67945 0.3048)
			(stroke
				(width 0.1)
				(type default)
			)
			(layer "B.Fab")
		)
		(fp_line
			(start -0.67945 0.3048)
			(end -0.120396 0.3048)
			(stroke
				(width 0.1)
				(type default)
			)
			(layer "B.Fab")
		)
		(fp_line
			(start -0.12065 -0.3048)
			(end -0.67945 -0.3048)
			(stroke
				(width 0.1)
				(type default)
			)
			(layer "B.Fab")
		)
		(fp_line
			(start -0.12065 -0.2794)
			(end -0.12065 -0.3048)
			(stroke
				(width 0.1)
				(type default)
			)
			(layer "B.Fab")
		)
		(fp_line
			(start -0.120396 0.2794)
			(end 0.12065 0.2794)
			(stroke
				(width 0.1)
				(type default)
			)
			(layer "B.Fab")
		)
		(fp_line
			(start -0.120396 0.3048)
			(end -0.120396 0.2794)
			(stroke
				(width 0.1)
				(type default)
			)
			(layer "B.Fab")
		)
		(fp_line
			(start 0.12065 -0.305054)
			(end 0.12065 -0.2794)
			(stroke
				(width 0.1)
				(type default)
			)
			(layer "B.Fab")
		)
		(fp_line
			(start 0.12065 -0.2794)
			(end -0.12065 -0.2794)
			(stroke
				(width 0.1)
				(type default)
			)
			(layer "B.Fab")
		)
		(fp_line
			(start 0.12065 0.2794)
			(end 0.12065 0.3048)
			(stroke
				(width 0.1)
				(type default)
			)
			(layer "B.Fab")
		)
		(fp_line
			(start 0.12065 0.3048)
			(end 0.67945 0.3048)
			(stroke
				(width 0.1)
				(type default)
			)
			(layer "B.Fab")
		)
		(fp_line
			(start 0.67945 -0.305054)
			(end 0.12065 -0.305054)
			(stroke
				(width 0.1)
				(type default)
			)
			(layer "B.Fab")
		)
		(fp_line
			(start 0.67945 0.3048)
			(end 0.67945 -0.305054)
			(stroke
				(width 0.1)
				(type default)
			)
			(layer "B.Fab")
		)
		(pad "1" smd circle
			(at 0.40005 0 180)
			(size 0 0)
			(layers "B.Cu" "B.Mask" "B.Paste")
			(net "LPC_ESPI_SEL_R")
		)
		(pad "2" smd circle
			(at -0.40005 0 180)
			(size 0 0)
			(layers "B.Cu" "B.Mask" "B.Paste")
			(net "GND")
		)
	)
	(footprint ""
		(layer "B.Cu")
		(at 41.966134 -44.92879 180)
		(property "Reference" "R166"
			(at 0 0 0)
			(layer "B.SilkS")
			(hide yes)
			(effects
				(font
					(size 1.27 1.27)
				)
				(justify mirror)
			)
		)
		(property "Value" ""
			(at 0 0 0)
			(layer "B.Fab")
			(effects
				(font
					(size 1.27 1.27)
				)
				(justify mirror)
			)
		)
		(duplicate_pad_numbers_are_jumpers no)
		(fp_line
			(start 0.7874 0.4064)
			(end 0.7874 -0.4064)
			(stroke
				(width 0.1524)
				(type default)
			)
			(layer "B.SilkS")
		)
		(fp_line
			(start 0.7874 -0.4064)
			(end -0.7874 -0.4064)
			(stroke
				(width 0.1524)
				(type default)
			)
			(layer "B.SilkS")
		)
		(fp_line
			(start -0.7874 0.4064)
			(end 0.7874 0.4064)
			(stroke
				(width 0.1524)
				(type default)
			)
			(layer "B.SilkS")
		)
		(fp_line
			(start -0.7874 -0.4064)
			(end -0.7874 0.4064)
			(stroke
				(width 0.1524)
				(type default)
			)
			(layer "B.SilkS")
		)
		(fp_line
			(start 0.67945 0.3048)
			(end 0.67945 -0.305054)
			(stroke
				(width 0.1)
				(type default)
			)
			(layer "B.Fab")
		)
		(fp_line
			(start 0.67945 -0.305054)
			(end 0.12065 -0.305054)
			(stroke
				(width 0.1)
				(type default)
			)
			(layer "B.Fab")
		)
		(fp_line
			(start 0.12065 0.3048)
			(end 0.67945 0.3048)
			(stroke
				(width 0.1)
				(type default)
			)
			(layer "B.Fab")
		)
		(fp_line
			(start 0.12065 0.2794)
			(end 0.12065 0.3048)
			(stroke
				(width 0.1)
				(type default)
			)
			(layer "B.Fab")
		)
		(fp_line
			(start 0.12065 -0.2794)
			(end -0.12065 -0.2794)
			(stroke
				(width 0.1)
				(type default)
			)
			(layer "B.Fab")
		)
		(fp_line
			(start 0.12065 -0.305054)
			(end 0.12065 -0.2794)
			(stroke
				(width 0.1)
				(type default)
			)
			(layer "B.Fab")
		)
		(fp_line
			(start -0.120396 0.3048)
			(end -0.120396 0.2794)
			(stroke
				(width 0.1)
				(type default)
			)
			(layer "B.Fab")
		)
		(fp_line
			(start -0.120396 0.2794)
			(end 0.12065 0.2794)
			(stroke
				(width 0.1)
				(type default)
			)
			(layer "B.Fab")
		)
		(fp_line
			(start -0.12065 -0.2794)
			(end -0.12065 -0.3048)
			(stroke
				(width 0.1)
				(type default)
			)
			(layer "B.Fab")
		)
		(fp_line
			(start -0.12065 -0.3048)
			(end -0.67945 -0.3048)
			(stroke
				(width 0.1)
				(type default)
			)
			(layer "B.Fab")
		)
		(fp_line
			(start -0.67945 0.3048)
			(end -0.120396 0.3048)
			(stroke
				(width 0.1)
				(type default)
			)
			(layer "B.Fab")
		)
		(fp_line
			(start -0.67945 -0.3048)
			(end -0.67945 0.3048)
			(stroke
				(width 0.1)
				(type default)
			)
			(layer "B.Fab")
		)
		(pad "1" smd circle
			(at 0.40005 0)
			(size 0 0)
			(layers "B.Cu" "B.Mask" "B.Paste")
			(net "IRQ_BMC_CPU_NMI_R")
		)
		(pad "2" smd circle
			(at -0.40005 0)
			(size 0 0)
			(layers "B.Cu" "B.Mask" "B.Paste")
			(net "IRQ_BMC_CPU_NMI")
		)
	)
	(footprint ""
		(layer "B.Cu")
		(at 39.414958 -82.836512 180)
		(property "Reference" "R430"
			(at 0 0 0)
			(layer "B.SilkS")
			(hide yes)
			(effects
				(font
					(size 1.27 1.27)
				)
				(justify mirror)
			)
		)
		(property "Value" ""
			(at 0 0 0)
			(layer "B.Fab")
			(effects
				(font
					(size 1.27 1.27)
				)
				(justify mirror)
			)
		)
		(duplicate_pad_numbers_are_jumpers no)
		(fp_line
			(start 0.7874 0.4064)
			(end 0.7874 -0.4064)
			(stroke
				(width 0.1524)
				(type default)
			)
			(layer "B.SilkS")
		)
		(fp_line
			(start 0.7874 -0.4064)
			(end -0.7874 -0.4064)
			(stroke
				(width 0.1524)
				(type default)
			)
			(layer "B.SilkS")
		)
		(fp_line
			(start -0.7874 0.4064)
			(end 0.7874 0.4064)
			(stroke
				(width 0.1524)
				(type default)
			)
			(layer "B.SilkS")
		)
		(fp_line
			(start -0.7874 -0.4064)
			(end -0.7874 0.4064)
			(stroke
				(width 0.1524)
				(type default)
			)
			(layer "B.SilkS")
		)
		(fp_line
			(start 0.67945 0.3048)
			(end 0.67945 -0.305054)
			(stroke
				(width 0.1)
				(type default)
			)
			(layer "B.Fab")
		)
		(fp_line
			(start 0.67945 -0.305054)
			(end 0.12065 -0.305054)
			(stroke
				(width 0.1)
				(type default)
			)
			(layer "B.Fab")
		)
		(fp_line
			(start 0.12065 0.3048)
			(end 0.67945 0.3048)
			(stroke
				(width 0.1)
				(type default)
			)
			(layer "B.Fab")
		)
		(fp_line
			(start 0.12065 0.2794)
			(end 0.12065 0.3048)
			(stroke
				(width 0.1)
				(type default)
			)
			(layer "B.Fab")
		)
		(fp_line
			(start 0.12065 -0.2794)
			(end -0.12065 -0.2794)
			(stroke
				(width 0.1)
				(type default)
			)
			(layer "B.Fab")
		)
		(fp_line
			(start 0.12065 -0.305054)
			(end 0.12065 -0.2794)
			(stroke
				(width 0.1)
				(type default)
			)
			(layer "B.Fab")
		)
		(fp_line
			(start -0.120396 0.3048)
			(end -0.120396 0.2794)
			(stroke
				(width 0.1)
				(type default)
			)
			(layer "B.Fab")
		)
		(fp_line
			(start -0.120396 0.2794)
			(end 0.12065 0.2794)
			(stroke
				(width 0.1)
				(type default)
			)
			(layer "B.Fab")
		)
		(fp_line
			(start -0.12065 -0.2794)
			(end -0.12065 -0.3048)
			(stroke
				(width 0.1)
				(type default)
			)
			(layer "B.Fab")
		)
		(fp_line
			(start -0.12065 -0.3048)
			(end -0.67945 -0.3048)
			(stroke
				(width 0.1)
				(type default)
			)
			(layer "B.Fab")
		)
		(fp_line
			(start -0.67945 0.3048)
			(end -0.120396 0.3048)
			(stroke
				(width 0.1)
				(type default)
			)
			(layer "B.Fab")
		)
		(fp_line
			(start -0.67945 -0.3048)
			(end -0.67945 0.3048)
			(stroke
				(width 0.1)
				(type default)
			)
			(layer "B.Fab")
		)
		(pad "1" smd circle
			(at 0.40005 0)
			(size 0 0)
			(layers "B.Cu" "B.Mask" "B.Paste")
			(net "P3V3_AUX")
		)
		(pad "2" smd circle
			(at -0.40005 0)
			(size 0 0)
			(layers "B.Cu" "B.Mask" "B.Paste")
			(net "FM_BMC_ONCTL_R_N")
		)
	)
	(footprint ""
		(layer "B.Cu")
		(at 78.7908 -33.4645 -90)
		(property "Reference" "R873"
			(at 0 0 90)
			(layer "B.SilkS")
			(hide yes)
			(effects
				(font
					(size 1.27 1.27)
				)
				(justify mirror)
			)
		)
		(property "Value" ""
			(at 0 0 90)
			(layer "B.Fab")
			(effects
				(font
					(size 1.27 1.27)
				)
				(justify mirror)
			)
		)
		(duplicate_pad_numbers_are_jumpers no)
		(fp_line
			(start -0.7874 0.4064)
			(end 0.7874 0.4064)
			(stroke
				(width 0.1524)
				(type default)
			)
			(layer "B.SilkS")
		)
		(fp_line
			(start 0.7874 0.4064)
			(end 0.7874 -0.4064)
			(stroke
				(width 0.1524)
				(type default)
			)
			(layer "B.SilkS")
		)
		(fp_line
			(start -0.7874 -0.4064)
			(end -0.7874 0.4064)
			(stroke
				(width 0.1524)
				(type default)
			)
			(layer "B.SilkS")
		)
		(fp_line
			(start 0.7874 -0.4064)
			(end -0.7874 -0.4064)
			(stroke
				(width 0.1524)
				(type default)
			)
			(layer "B.SilkS")
		)
		(fp_line
			(start -0.67945 0.3048)
			(end -0.120396 0.3048)
			(stroke
				(width 0.1)
				(type default)
			)
			(layer "B.Fab")
		)
		(fp_line
			(start -0.120396 0.3048)
			(end -0.120396 0.2794)
			(stroke
				(width 0.1)
				(type default)
			)
			(layer "B.Fab")
		)
		(fp_line
			(start 0.12065 0.3048)
			(end 0.67945 0.3048)
			(stroke
				(width 0.1)
				(type default)
			)
			(layer "B.Fab")
		)
		(fp_line
			(start 0.67945 0.3048)
			(end 0.67945 -0.305054)
			(stroke
				(width 0.1)
				(type default)
			)
			(layer "B.Fab")
		)
		(fp_line
			(start -0.120396 0.2794)
			(end 0.12065 0.2794)
			(stroke
				(width 0.1)
				(type default)
			)
			(layer "B.Fab")
		)
		(fp_line
			(start 0.12065 0.2794)
			(end 0.12065 0.3048)
			(stroke
				(width 0.1)
				(type default)
			)
			(layer "B.Fab")
		)
		(fp_line
			(start -0.12065 -0.2794)
			(end -0.12065 -0.3048)
			(stroke
				(width 0.1)
				(type default)
			)
			(layer "B.Fab")
		)
		(fp_line
			(start 0.12065 -0.2794)
			(end -0.12065 -0.2794)
			(stroke
				(width 0.1)
				(type default)
			)
			(layer "B.Fab")
		)
		(fp_line
			(start -0.67945 -0.3048)
			(end -0.67945 0.3048)
			(stroke
				(width 0.1)
				(type default)
			)
			(layer "B.Fab")
		)
		(fp_line
			(start -0.12065 -0.3048)
			(end -0.67945 -0.3048)
			(stroke
				(width 0.1)
				(type default)
			)
			(layer "B.Fab")
		)
		(fp_line
			(start 0.12065 -0.305054)
			(end 0.12065 -0.2794)
			(stroke
				(width 0.1)
				(type default)
			)
			(layer "B.Fab")
		)
		(fp_line
			(start 0.67945 -0.305054)
			(end 0.12065 -0.305054)
			(stroke
				(width 0.1)
				(type default)
			)
			(layer "B.Fab")
		)
		(pad "1" smd circle
			(at 0.40005 0 90)
			(size 0 0)
			(layers "B.Cu" "B.Mask" "B.Paste")
			(net "PWRGD_P2V5_AUX_R3")
		)
		(pad "2" smd circle
			(at -0.40005 0 90)
			(size 0 0)
			(layers "B.Cu" "B.Mask" "B.Paste")
			(net "PWRGD_P2V5_AUX")
		)
	)
)
